# S9S_MB_2U (Grand Teton) — schematic netlist excerpt (pin names and nets, part order shuffled) for the footprints in the layout excerpt that follows; sources: Cadence DE-HDL packaged netlist, KiCad conversion of 03242023_DA0F0TMBIJ0_F0T_Motherboard_J_brd_V01_OCP.brd

R447  Q_RES  1 1% CHIP  pkg 0603LF  page 210 : A = P3V3_AUX_CLK_GEN_VDDMXCK_CK440 ; B = P3V3_AUX_CLK_GEN_VDDPT_CK440
R987  Q_RES  33.2 1% CHIP  pkg 0402LF  page 222 : A = FM_PVCCINFAON_CPU1_R_EN ; B = FM_PVCCINFAON_CPU1_EN

(kicad_pcb
	(version 20260206)
	(generator "pcbnew")
	(generator_version "10.0")
	(general
		(thickness 1.6)
		(legacy_teardrops no)
	)
	(paper "A4")
	(title_block
		(title "03242023_DA0F0TMBIJ0_F0T_Motherboard_J_brd_V01_OCP.brd")
		(comment 1 "Grand Teton / footprints 5257-5258 of 6105")
	)
	(layers
		(0 "F.Cu" signal "TOP")
		(4 "In1.Cu" signal "GND")
		(6 "In2.Cu" signal "IN1")
		(8 "In3.Cu" signal "GND1")
		(10 "In4.Cu" signal "IN2")
		(12 "In5.Cu" signal "GND2")
		(14 "In6.Cu" signal "IN3")
		(16 "In7.Cu" signal "GND3")
		(18 "In8.Cu" signal "VCC")
		(20 "In9.Cu" signal "VCC1")
		(22 "In10.Cu" signal "GND4")
		(24 "In11.Cu" signal "IN4")
		(26 "In12.Cu" signal "GND5")
		(28 "In13.Cu" signal "IN5")
		(30 "In14.Cu" signal "GND6")
		(32 "In15.Cu" signal "IN6")
		(34 "In16.Cu" signal "GND7")
		(2 "B.Cu" signal "BOTTOM")
		(9 "F.Adhes" user "F.Adhesive")
		(11 "B.Adhes" user "B.Adhesive")
		(13 "F.Paste" user "Package Geometry/Pastemask Top")
		(15 "B.Paste" user "Package Geometry/Pastemask Bottom")
		(5 "F.SilkS" user "Ref Des/Silkscreen Top")
		(7 "B.SilkS" user "Ref Des/Silkscreen Bottom")
		(1 "F.Mask" user "Board Geometry/Soldermask Top")
		(3 "B.Mask" user "Board Geometry/Soldermask Bottom")
		(17 "Dwgs.User" user "User.Drawings")
		(19 "Cmts.User" user "User.Comments")
		(21 "Eco1.User" user "User.Eco1")
		(23 "Eco2.User" user "User.Eco2")
		(25 "Edge.Cuts" user "Board Geometry/Outline")
		(27 "Margin" user)
		(31 "F.CrtYd" user "Package Geometry/Place Bound Top")
		(29 "B.CrtYd" user "Package Geometry/Place Bound Bottom")
		(35 "F.Fab" user "Ref Des/Assembly Top")
		(33 "B.Fab" user "Ref Des/Assembly Bottom")
	)
	(footprint ""
		(layer "B.Cu")
		(at 160.83788 -121.376948)
		(property "Reference" "R987"
			(at 0 0 0)
			(layer "B.SilkS")
			(hide yes)
			(effects
				(font
					(size 1.27 1.27)
				)
				(justify mirror)
			)
		)
		(property "Value" ""
			(at 0 0 0)
			(layer "B.Fab")
			(effects
				(font
					(size 1.27 1.27)
				)
				(justify mirror)
			)
		)
		(duplicate_pad_numbers_are_jumpers no)
		(fp_line
			(start -0.7874 -0.4064)
			(end -0.7874 0.4064)
			(stroke
				(width 0.1524)
				(type default)
			)
			(layer "B.SilkS")
		)
		(fp_line
			(start -0.7874 0.4064)
			(end 0.7874 0.4064)
			(stroke
				(width 0.1524)
				(type default)
			)
			(layer "B.SilkS")
		)
		(fp_line
			(start 0.7874 -0.4064)
			(end -0.7874 -0.4064)
			(stroke
				(width 0.1524)
				(type default)
			)
			(layer "B.SilkS")
		)
		(fp_line
			(start 0.7874 0.4064)
			(end 0.7874 -0.4064)
			(stroke
				(width 0.1524)
				(type default)
			)
			(layer "B.SilkS")
		)
		(fp_line
			(start -0.67945 -0.3048)
			(end -0.67945 0.3048)
			(stroke
				(width 0.1)
				(type default)
			)
			(layer "B.Fab")
		)
		(fp_line
			(start -0.67945 0.3048)
			(end -0.120396 0.3048)
			(stroke
				(width 0.1)
				(type default)
			)
			(layer "B.Fab")
		)
		(fp_line
			(start -0.12065 -0.3048)
			(end -0.67945 -0.3048)
			(stroke
				(width 0.1)
				(type default)
			)
			(layer "B.Fab")
		)
		(fp_line
			(start -0.12065 -0.2794)
			(end -0.12065 -0.3048)
			(stroke
				(width 0.1)
				(type default)
			)
			(layer "B.Fab")
		)
		(fp_line
			(start -0.120396 0.2794)
			(end 0.12065 0.2794)
			(stroke
				(width 0.1)
				(type default)
			)
			(layer "B.Fab")
		)
		(fp_line
			(start -0.120396 0.3048)
			(end -0.120396 0.2794)
			(stroke
				(width 0.1)
				(type default)
			)
			(layer "B.Fab")
		)
		(fp_line
			(start 0.12065 -0.305054)
			(end 0.12065 -0.2794)
			(stroke
				(width 0.1)
				(type default)
			)
			(layer "B.Fab")
		)
		(fp_line
			(start 0.12065 -0.2794)
			(end -0.12065 -0.2794)
			(stroke
				(width 0.1)
				(type default)
			)
			(layer "B.Fab")
		)
		(fp_line
			(start 0.12065 0.2794)
			(end 0.12065 0.3048)
			(stroke
				(width 0.1)
				(type default)
			)
			(layer "B.Fab")
		)
		(fp_line
			(start 0.12065 0.3048)
			(end 0.67945 0.3048)
			(stroke
				(width 0.1)
				(type default)
			)
			(layer "B.Fab")
		)
		(fp_line
			(start 0.67945 -0.305054)
			(end 0.12065 -0.305054)
			(stroke
				(width 0.1)
				(type default)
			)
			(layer "B.Fab")
		)
		(fp_line
			(start 0.67945 0.3048)
			(end 0.67945 -0.305054)
			(stroke
				(width 0.1)
				(type default)
			)
			(layer "B.Fab")
		)
		(pad "1" smd circle
			(at 0.40005 0 180)
			(size 0 0)
			(layers "B.Cu" "B.Mask" "B.Paste")
			(net "FM_PVCCINFAON_CPU1_R_EN")
		)
		(pad "2" smd circle
			(at -0.40005 0 180)
			(size 0 0)
			(layers "B.Cu" "B.Mask" "B.Paste")
			(net "FM_PVCCINFAON_CPU1_EN")
		)
	)
	(footprint ""
		(layer "B.Cu")
		(at 261.375906 -104.832912 180)
		(property "Reference" "R447"
			(at 0 0 0)
			(layer "B.SilkS")
			(hide yes)
			(effects
				(font
					(size 1.27 1.27)
				)
				(justify mirror)
			)
		)
		(property "Value" ""
			(at 0 0 0)
			(layer "B.Fab")
			(effects
				(font
					(size 1.27 1.27)
				)
				(justify mirror)
			)
		)
		(duplicate_pad_numbers_are_jumpers no)
		(fp_line
			(start 1.2954 0.5842)
			(end 1.2954 -0.5842)
			(stroke
				(width 0.1524)
				(type default)
			)
			(layer "B.SilkS")
		)
		(fp_line
			(start 1.2954 -0.5842)
			(end -1.2954 -0.5842)
			(stroke
				(width 0.1524)
				(type default)
			)
			(layer "B.SilkS")
		)
		(fp_line
			(start -1.2954 0.5842)
			(end 1.2954 0.5842)
			(stroke
				(width 0.1524)
				(type default)
			)
			(layer "B.SilkS")
		)
		(fp_line
			(start -1.2954 -0.5842)
			(end -1.2954 0.5842)
			(stroke
				(width 0.1524)
				(type default)
			)
			(layer "B.SilkS")
		)
		(fp_line
			(start 1.1938 0.4064)
			(end 1.1938 -0.406654)
			(stroke
				(width 0.1)
				(type default)
			)
			(layer "B.Fab")
		)
		(fp_line
			(start 1.1938 -0.406654)
			(end 0.8636 -0.406654)
			(stroke
				(width 0.1)
				(type default)
			)
			(layer "B.Fab")
		)
		(fp_line
			(start 0.8636 0.4572)
			(end 0.8636 0.4318)
			(stroke
				(width 0.1)
				(type default)
			)
			(layer "B.Fab")
		)
		(fp_line
			(start 0.8636 0.4318)
			(end 0.8636 0.4064)
			(stroke
				(width 0.1)
				(type default)
			)
			(layer "B.Fab")
		)
		(fp_line
			(start 0.8636 0.4064)
			(end 1.1938 0.4064)
			(stroke
				(width 0.1)
				(type default)
			)
			(layer "B.Fab")
		)
		(fp_line
			(start 0.8636 -0.406654)
			(end 0.8636 -0.4572)
			(stroke
				(width 0.1)
				(type default)
			)
			(layer "B.Fab")
		)
		(fp_line
			(start 0.8636 -0.4572)
			(end -0.8636 -0.4572)
			(stroke
				(width 0.1)
				(type default)
			)
			(layer "B.Fab")
		)
		(fp_line
			(start -0.8636 0.4572)
			(end 0.8636 0.4572)
			(stroke
				(width 0.1)
				(type default)
			)
			(layer "B.Fab")
		)
		(fp_line
			(start -0.8636 0.4064)
			(end -0.8636 0.4572)
			(stroke
				(width 0.1)
				(type default)
			)
			(layer "B.Fab")
		)
		(fp_line
			(start -0.8636 -0.406654)
			(end -1.1938 -0.406654)
			(stroke
				(width 0.1)
				(type default)
			)
			(layer "B.Fab")
		)
		(fp_line
			(start -0.8636 -0.4572)
			(end -0.8636 -0.406654)
			(stroke
				(width 0.1)
				(type default)
			)
			(layer "B.Fab")
		)
		(fp_line
			(start -1.1938 0.4064)
			(end -0.8636 0.4064)
			(stroke
				(width 0.1)
				(type default)
			)
			(layer "B.Fab")
		)
		(fp_line
			(start -1.1938 -0.406654)
			(end -1.1938 0.4064)
			(stroke
				(width 0.1)
				(type default)
			)
			(layer "B.Fab")
		)
		(pad "1" smd rect
			(at 0.7366 0 90)
			(size 0.7112 0.8128)
			(layers "B.Cu" "B.Mask" "B.Paste")
			(net "P3V3_AUX_CLK_GEN_VDDMXCK_CK440")
		)
		(pad "2" smd rect
			(at -0.7366 0 90)
			(size 0.7112 0.8128)
			(layers "B.Cu" "B.Mask" "B.Paste")
			(net "P3V3_AUX_CLK_GEN_VDDPT_CK440")
		)
	)
)
